# S9S_MB_2U (Grand Teton) — schematic netlist excerpt (pin names and nets, part order shuffled) for the footprints in the layout excerpt that follows; sources: Cadence DE-HDL packaged netlist, KiCad conversion of 03242023_DA0F0TMBIJ0_F0T_Motherboard_J_brd_V01_OCP.brd

R835  Q_RES  0 5% CHIP  pkg 0402LF  page 129 : A = RST_PLD_CPU0_DRAM_GH_N ; B = RST_M_GH_CPU0_FPGA_N
C24  Q_CAP  10UF 16V 10% X6S  pkg C0805  page 89 : A = P12V_S3_AUX_CPU0_NVDIMM ; B = GND
R3212  Q_RES  22 1% EMPTY  pkg 0402LF  page 160 : A = NCSI_BMC_RXD1_R1 ; B = RMII_OCP_BMC_RXD_1

(kicad_pcb
	(version 20260206)
	(generator "pcbnew")
	(generator_version "10.0")
	(general
		(thickness 1.6)
		(legacy_teardrops no)
	)
	(paper "A4")
	(title_block
		(title "03242023_DA0F0TMBIJ0_F0T_Motherboard_J_brd_V01_OCP.brd")
		(comment 1 "Grand Teton / footprints 4813-4815 of 6105")
	)
	(layers
		(0 "F.Cu" signal "TOP")
		(4 "In1.Cu" signal "GND")
		(6 "In2.Cu" signal "IN1")
		(8 "In3.Cu" signal "GND1")
		(10 "In4.Cu" signal "IN2")
		(12 "In5.Cu" signal "GND2")
		(14 "In6.Cu" signal "IN3")
		(16 "In7.Cu" signal "GND3")
		(18 "In8.Cu" signal "VCC")
		(20 "In9.Cu" signal "VCC1")
		(22 "In10.Cu" signal "GND4")
		(24 "In11.Cu" signal "IN4")
		(26 "In12.Cu" signal "GND5")
		(28 "In13.Cu" signal "IN5")
		(30 "In14.Cu" signal "GND6")
		(32 "In15.Cu" signal "IN6")
		(34 "In16.Cu" signal "GND7")
		(2 "B.Cu" signal "BOTTOM")
		(9 "F.Adhes" user "F.Adhesive")
		(11 "B.Adhes" user "B.Adhesive")
		(13 "F.Paste" user "Package Geometry/Pastemask Top")
		(15 "B.Paste" user "Package Geometry/Pastemask Bottom")
		(5 "F.SilkS" user "Ref Des/Silkscreen Top")
		(7 "B.SilkS" user "Ref Des/Silkscreen Bottom")
		(1 "F.Mask" user "Board Geometry/Soldermask Top")
		(3 "B.Mask" user "Board Geometry/Soldermask Bottom")
		(17 "Dwgs.User" user "User.Drawings")
		(19 "Cmts.User" user "User.Comments")
		(21 "Eco1.User" user "User.Eco1")
		(23 "Eco2.User" user "User.Eco2")
		(25 "Edge.Cuts" user "Board Geometry/Outline")
		(27 "Margin" user)
		(31 "F.CrtYd" user "Package Geometry/Place Bound Top")
		(29 "B.CrtYd" user "Package Geometry/Place Bound Bottom")
		(35 "F.Fab" user "Ref Des/Assembly Top")
		(33 "B.Fab" user "Ref Des/Assembly Bottom")
	)
	(footprint ""
		(layer "B.Cu")
		(at 216.25306 -78.448408 180)
		(property "Reference" "R3212"
			(at 0 0 0)
			(layer "B.SilkS")
			(hide yes)
			(effects
				(font
					(size 1.27 1.27)
				)
				(justify mirror)
			)
		)
		(property "Value" ""
			(at 0 0 0)
			(layer "B.Fab")
			(effects
				(font
					(size 1.27 1.27)
				)
				(justify mirror)
			)
		)
		(duplicate_pad_numbers_are_jumpers no)
		(fp_line
			(start 0.7874 0.4064)
			(end 0.7874 -0.4064)
			(stroke
				(width 0.1524)
				(type default)
			)
			(layer "B.SilkS")
		)
		(fp_line
			(start 0.7874 -0.4064)
			(end -0.7874 -0.4064)
			(stroke
				(width 0.1524)
				(type default)
			)
			(layer "B.SilkS")
		)
		(fp_line
			(start -0.7874 0.4064)
			(end 0.7874 0.4064)
			(stroke
				(width 0.1524)
				(type default)
			)
			(layer "B.SilkS")
		)
		(fp_line
			(start -0.7874 -0.4064)
			(end -0.7874 0.4064)
			(stroke
				(width 0.1524)
				(type default)
			)
			(layer "B.SilkS")
		)
		(fp_line
			(start 0.67945 0.3048)
			(end 0.67945 -0.305054)
			(stroke
				(width 0.1)
				(type default)
			)
			(layer "B.Fab")
		)
		(fp_line
			(start 0.67945 -0.305054)
			(end 0.12065 -0.305054)
			(stroke
				(width 0.1)
				(type default)
			)
			(layer "B.Fab")
		)
		(fp_line
			(start 0.12065 0.3048)
			(end 0.67945 0.3048)
			(stroke
				(width 0.1)
				(type default)
			)
			(layer "B.Fab")
		)
		(fp_line
			(start 0.12065 0.2794)
			(end 0.12065 0.3048)
			(stroke
				(width 0.1)
				(type default)
			)
			(layer "B.Fab")
		)
		(fp_line
			(start 0.12065 -0.2794)
			(end -0.12065 -0.2794)
			(stroke
				(width 0.1)
				(type default)
			)
			(layer "B.Fab")
		)
		(fp_line
			(start 0.12065 -0.305054)
			(end 0.12065 -0.2794)
			(stroke
				(width 0.1)
				(type default)
			)
			(layer "B.Fab")
		)
		(fp_line
			(start -0.120396 0.3048)
			(end -0.120396 0.2794)
			(stroke
				(width 0.1)
				(type default)
			)
			(layer "B.Fab")
		)
		(fp_line
			(start -0.120396 0.2794)
			(end 0.12065 0.2794)
			(stroke
				(width 0.1)
				(type default)
			)
			(layer "B.Fab")
		)
		(fp_line
			(start -0.12065 -0.2794)
			(end -0.12065 -0.3048)
			(stroke
				(width 0.1)
				(type default)
			)
			(layer "B.Fab")
		)
		(fp_line
			(start -0.12065 -0.3048)
			(end -0.67945 -0.3048)
			(stroke
				(width 0.1)
				(type default)
			)
			(layer "B.Fab")
		)
		(fp_line
			(start -0.67945 0.3048)
			(end -0.120396 0.3048)
			(stroke
				(width 0.1)
				(type default)
			)
			(layer "B.Fab")
		)
		(fp_line
			(start -0.67945 -0.3048)
			(end -0.67945 0.3048)
			(stroke
				(width 0.1)
				(type default)
			)
			(layer "B.Fab")
		)
		(pad "1" smd circle
			(at 0.40005 0)
			(size 0 0)
			(layers "B.Cu" "B.Mask" "B.Paste")
			(net "NCSI_BMC_RXD1_R1")
		)
		(pad "2" smd circle
			(at -0.40005 0)
			(size 0 0)
			(layers "B.Cu" "B.Mask" "B.Paste")
			(net "RMII_OCP_BMC_RXD_1")
		)
	)
	(footprint ""
		(layer "B.Cu")
		(at 267.701014 -321.549776 -90)
		(property "Reference" "C24"
			(at 0 0 90)
			(layer "B.SilkS")
			(hide yes)
			(effects
				(font
					(size 1.27 1.27)
				)
				(justify mirror)
			)
		)
		(property "Value" ""
			(at 0 0 90)
			(layer "B.Fab")
			(effects
				(font
					(size 1.27 1.27)
				)
				(justify mirror)
			)
		)
		(duplicate_pad_numbers_are_jumpers no)
		(fp_line
			(start -1.524 0.762)
			(end 1.524 0.762)
			(stroke
				(width 0.1524)
				(type default)
			)
			(layer "B.SilkS")
		)
		(fp_line
			(start 1.524 0.762)
			(end 1.524 -0.762)
			(stroke
				(width 0.1524)
				(type default)
			)
			(layer "B.SilkS")
		)
		(fp_line
			(start -1.524 -0.762)
			(end -1.524 0.762)
			(stroke
				(width 0.1524)
				(type default)
			)
			(layer "B.SilkS")
		)
		(fp_line
			(start 1.524 -0.762)
			(end -1.524 -0.762)
			(stroke
				(width 0.1524)
				(type default)
			)
			(layer "B.SilkS")
		)
		(fp_line
			(start -1.1049 0.724916)
			(end -1.1049 -0.724916)
			(stroke
				(width 0.1)
				(type default)
			)
			(layer "B.Fab")
		)
		(fp_line
			(start 1.1049 0.724916)
			(end -1.1049 0.724916)
			(stroke
				(width 0.1)
				(type default)
			)
			(layer "B.Fab")
		)
		(fp_line
			(start -1.1049 -0.724916)
			(end 1.1049 -0.724916)
			(stroke
				(width 0.1)
				(type default)
			)
			(layer "B.Fab")
		)
		(fp_line
			(start 1.1049 -0.724916)
			(end 1.1049 0.724916)
			(stroke
				(width 0.1)
				(type default)
			)
			(layer "B.Fab")
		)
		(pad "1" smd rect
			(at 0.889 0 270)
			(size 1.016 1.27)
			(layers "B.Cu" "B.Mask" "B.Paste")
			(net "P12V_S3_AUX_CPU0_NVDIMM")
		)
		(pad "2" smd rect
			(at -0.889 0 270)
			(size 1.016 1.27)
			(layers "B.Cu" "B.Mask" "B.Paste")
			(net "GND")
		)
	)
	(footprint ""
		(layer "B.Cu")
		(at 434.57241 -193.567304 -90)
		(property "Reference" "R835"
			(at 0 0 90)
			(layer "B.SilkS")
			(hide yes)
			(effects
				(font
					(size 1.27 1.27)
				)
				(justify mirror)
			)
		)
		(property "Value" ""
			(at 0 0 90)
			(layer "B.Fab")
			(effects
				(font
					(size 1.27 1.27)
				)
				(justify mirror)
			)
		)
		(duplicate_pad_numbers_are_jumpers no)
		(fp_line
			(start -0.7874 0.4064)
			(end 0.7874 0.4064)
			(stroke
				(width 0.1524)
				(type default)
			)
			(layer "B.SilkS")
		)
		(fp_line
			(start 0.7874 0.4064)
			(end 0.7874 -0.4064)
			(stroke
				(width 0.1524)
				(type default)
			)
			(layer "B.SilkS")
		)
		(fp_line
			(start -0.7874 -0.4064)
			(end -0.7874 0.4064)
			(stroke
				(width 0.1524)
				(type default)
			)
			(layer "B.SilkS")
		)
		(fp_line
			(start 0.7874 -0.4064)
			(end -0.7874 -0.4064)
			(stroke
				(width 0.1524)
				(type default)
			)
			(layer "B.SilkS")
		)
		(fp_line
			(start -0.67945 0.3048)
			(end -0.120396 0.3048)
			(stroke
				(width 0.1)
				(type default)
			)
			(layer "B.Fab")
		)
		(fp_line
			(start -0.120396 0.3048)
			(end -0.120396 0.2794)
			(stroke
				(width 0.1)
				(type default)
			)
			(layer "B.Fab")
		)
		(fp_line
			(start 0.12065 0.3048)
			(end 0.67945 0.3048)
			(stroke
				(width 0.1)
				(type default)
			)
			(layer "B.Fab")
		)
		(fp_line
			(start 0.67945 0.3048)
			(end 0.67945 -0.305054)
			(stroke
				(width 0.1)
				(type default)
			)
			(layer "B.Fab")
		)
		(fp_line
			(start -0.120396 0.2794)
			(end 0.12065 0.2794)
			(stroke
				(width 0.1)
				(type default)
			)
			(layer "B.Fab")
		)
		(fp_line
			(start 0.12065 0.2794)
			(end 0.12065 0.3048)
			(stroke
				(width 0.1)
				(type default)
			)
			(layer "B.Fab")
		)
		(fp_line
			(start -0.12065 -0.2794)
			(end -0.12065 -0.3048)
			(stroke
				(width 0.1)
				(type default)
			)
			(layer "B.Fab")
		)
		(fp_line
			(start 0.12065 -0.2794)
			(end -0.12065 -0.2794)
			(stroke
				(width 0.1)
				(type default)
			)
			(layer "B.Fab")
		)
		(fp_line
			(start -0.67945 -0.3048)
			(end -0.67945 0.3048)
			(stroke
				(width 0.1)
				(type default)
			)
			(layer "B.Fab")
		)
		(fp_line
			(start -0.12065 -0.3048)
			(end -0.67945 -0.3048)
			(stroke
				(width 0.1)
				(type default)
			)
			(layer "B.Fab")
		)
		(fp_line
			(start 0.12065 -0.305054)
			(end 0.12065 -0.2794)
			(stroke
				(width 0.1)
				(type default)
			)
			(layer "B.Fab")
		)
		(fp_line
			(start 0.67945 -0.305054)
			(end 0.12065 -0.305054)
			(stroke
				(width 0.1)
				(type default)
			)
			(layer "B.Fab")
		)
		(pad "1" smd circle
			(at 0.40005 0 90)
			(size 0 0)
			(layers "B.Cu" "B.Mask" "B.Paste")
			(net "RST_PLD_CPU0_DRAM_GH_N")
		)
		(pad "2" smd circle
			(at -0.40005 0 90)
			(size 0 0)
			(layers "B.Cu" "B.Mask" "B.Paste")
			(net "RST_M_GH_CPU0_FPGA_N")
		)
	)
)
